FILE_TYPE = CONNECTIVITY;
{Allegro Design Entry HDL 16.6-p007 (v16-6-112F) 10/10/2012}
"PAGE_NUMBER" = 176;
0"NC";
1"P5V\g";
2"GND\g";
3"GND\g";
4"P3V3_STBY\g";
5"GND\g";
6"GND\g";
7"GND\g";
8"P3V3_STBY\g";
9"P5V_STBY\g";
10"P3V3_STBY\g";
11"GND\g";
12"P3V3_STBY\g";
13"GND\g";
14"GND\g";
15"P3V3_STBY\g";
16"P3V3_STBY\g";
17"P3V3_STBY\g";
18"P3V3_STBY\g";
19"P3V3_STBY\g";
20"P3V3_STBY\g";
21"GND\g";
22"GND\g";
23"GND\g";
24"GND\g";
25"SPA_MID_DBG2_RX_BUF";
26"SPA_MID_DBG_RX";
27"SPA_MID_DBG1_RX";
28"DEBUG_CARD2_PRSNT";
29"DEBUG_CARD2_PRSNT";
30"SPA_MID_DBG2_RX";
31"USB2_P01_ESD_DN";
32"SPA_MID_DBG2_RX";
33"USB2_P01_ESD_DP";
34"USB2_P01_DP";
35"USB2_P01_DN";
36"FM_CPLD_USB_P0_EN_N";
37"FM_USB_P0_EN_R_N";
38"TP_USB_ESD_AC3";
39"TP_USB_ESD_AC2";
40"P5V_USB"VOLTAGE"5V";
41"SPA_MID_DBG2_TX_R";
42"SPA_MID_DBG1_TX_R";
43"SMB_DEBUG_STBY_LVC3_SDA_R1";
44"SPA_MID_DBG2_TX";
45"DEBUG_CARD2_PRSNT";
46"SMB_DEBUG_STBY_LVC3_SCL_CONN";
47"SMB_DEBUG_STBY_LVC3_SDA_CONN";
48"SPA_MID_DBG_TX";
49"SMB_DEBUG_STBY_LVC3_SCL_R1";
50"SMB_DEBUG_STBY_LVC3_SCL_R1";
51"SMB_DEBUG_STBY_LVC3_SDA_CONN";
52"SMB_DEBUG_STBY_LVC3_SCL_CONN";
53"DEBUG_CARD2_PRSNT";
54"SMB_DEBUG_STBY_LVC3_SCL_CONN";
55"SMB_DEBUG_STBY_LVC3_SDA_CONN";
56"SMB_DEBUG_STBY_LVC3_SDA";
57"SMB_DEBUG_STBY_LVC3_SCL";
58"FM_USB_P0_EN_BOOT_BIOS_STRAP_N";
59"FM_OC0_USB_N";
60"SPA_MID_DBG1_TX_EN";
61"TP_USB_ESD_OUT3";
62"TP_USB_ESD_OUT2";
63"DEBUG_CARD2_PRSNT";
64"P5V_USB";
65"P5V_TPS2061";
66"SPA_MID_DBG1_TX";
67"SPA_MID_DBG2_TX";
68"SMB_DEBUG_STBY_LVC3_SDA_R1";
69"SMB_DEBUG_STBY_LVC3_SDA_R1";
70"SMB_DEBUG_STBY_LVC3_SCL_R1";
%"TPS2061"
"1","(-4125,3325)","0","mstr_vreg","I100";
;
CDS_SEC"1"
CDS_LOCATION"U1M3"
LOCATION"U1M3"
MATERIAL"IC"
PART_NUMBER"H66405-001"
ROOM"USB_REAR"
SEC"1"
BOM_COST"MIO_USB"
SEC_TYPE"SM"
PACK_TYPE"SM"
CDS_LIB"mstr_vreg";
"IN"
$PN"5"65;
"EN_N"
$PN"4"37;
"OUT"
$PN"1"64;
"GND"
$PN"2"2;
"OC_N"
$PN"3"59;
%"P5V"
"1","(-4950,4150)","0","mstr_symbols","I101";
;
HDL_POWER"P5V"
BODY_TYPE"PLUMBING"
VOLTAGE"5.0V"
SIZE"1B"
CDS_LIB"mstr_symbols";
"G\NAC"1;
%"GND"
"1","(-3750,2950)","0","mstr_symbols","I102";
;
HDL_POWER"GND"
BODY_TYPE"PLUMBING"
SIZE"1B"
VOLTAGE"0"
CDS_LIB"mstr_symbols";
"A\NAC"2;
%"RES"
"2","(-3700,3675)","0","mstr_discrete","I105";
;
CDS_SEC"1"
CDS_LOCATION"R1M24"
LOCATION"R1M24"
PART_NUMBER"G21796-016"
WATTAGE"1/16W"
MATERIAL"CHIP"
PACK_TYPE"0402"
TOLERANCE"1%"
VALUE"10.0K"
CDS_LIB"mstr_discrete"
ROOM"USB_REAR"
SEC"1"
SEC_TYPE"0402"
BOM_COST"MIO_USB";
"A"
$PN"1"4;
"B"
$PN"2"59;
%"CAP_A"
"1","(-5225,3525)","0","dev_discrete","I108";
;
CDS_LOCATION"C1M38"
PACK_TYPE"0402V"
LOCATION"C1M38"
TOLERANCE"10%"
VOLTAGE"16V"
VALUE"0.1UF"
PART_NUMBER"A36096-030"
MATERIAL"X7R"
BOM_COST"MIO_USB"
SEC_TYPE"0402V"
SEC"1"
CDS_SEC"1"
ROOM"USB_REAR"
CDS_LIB"dev_discrete";
"B"
$PN"2"3;
"A"
$PN"1"65;
%"GND"
"1","(-5225,3325)","0","mstr_symbols","I109";
;
HDL_POWER"GND"
BODY_TYPE"PLUMBING"
SIZE"1B"
VOLTAGE"0"
CDS_LIB"mstr_symbols";
"A\NAC"3;
%"P3V3_STBY"
"1","(-3700,3875)","0","mstr_symbols","I110";
;
CDS_LIB"mstr_symbols"
SIZE"1B"
VOLTAGE"3.3V"
BODY_TYPE"PLUMBING"
HDL_POWER"P3V3_STBY";
"G\NAC"4;
%"RES"
"2","(-5200,3000)","0","mstr_discrete","I111";
;
CDS_SEC"1"
CDS_LOCATION"R1M25"
VALUE"10.0K"
LOCATION"R1M25"
PACK_TYPE"0402"
WATTAGE"1/16W"
MATERIAL"CHIP"
PART_NUMBER"G21796-016"
TOLERANCE"1%"
BOM_COST"MIO_USB"
SEC_TYPE"0402"
SEC"1"
CDS_LIB"mstr_discrete"
ROOM"USB_REAR";
"A"
$PN"1"37;
"B"
$PN"2"5;
%"GND"
"1","(-5200,2775)","0","mstr_symbols","I112";
;
HDL_POWER"GND"
BODY_TYPE"PLUMBING"
SIZE"1B"
CDS_LIB"mstr_symbols"
VOLTAGE"0";
"A\NAC"5;
%"CAPP"
"1","(-3650,3150)","0","mstr_discrete","I113";
;
CDS_SEC"1"
CDS_LOCATION"C9B8"
PART_NUMBER"724613-043"
MATERIAL"POSCAP"
PACK_TYPE"7343HLF"
VALUE"330UF"
TOLERANCE"20%"
LOCATION"C9B8"
VOLTAGE"10V"
CDS_LIB"mstr_discrete"
SEC_TYPE"7343HLF"
SEC"1";
"B"
$PN"2"6;
"A"
$PN"1"64;
%"GND"
"1","(-3650,2950)","0","mstr_symbols","I114";
;
SIZE"1B"
VOLTAGE"0"
CDS_LIB"mstr_symbols"
BODY_TYPE"PLUMBING"
HDL_POWER"GND";
"A\NAC"6;
%"GND"
"1","(-200,1325)","0","mstr_symbols","I125";
;
HDL_POWER"GND"
BODY_TYPE"PLUMBING"
VOLTAGE"0.0V"
CDS_LIB"mstr_symbols"
SIZE"1B";
"A\NAC"7;
%"P3V3_STBY"
"1","(-200,1750)","0","mstr_symbols","I126";
;
HDL_POWER"P3V3_STBY"
BODY_TYPE"PLUMBING"
VOLTAGE"3.3V"
CDS_LIB"mstr_symbols"
SIZE"1B";
"G\NAC"8;
%"RES"
"1","(-5350,3950)","5","mstr_discrete","I132";
;
CDS_SEC"1"
CDS_LOCATION"R1W10"
LOCATION"R1W10"
MATERIAL"CHIP"
WATTAGE"1/8W"
VALUE"0.0"
PACK_TYPE"0805"
TOLERANCE"5%"
PART_NUMBER"G22179-004"
SEC"1"
SEC_TYPE"0805"
CDS_LIB"mstr_discrete"
ROOM"HOT_SWAP";
"B"
$PN"2"65;
"A"
$PN"1"9;
%"RES"
"1","(-4950,3950)","5","mstr_discrete","I133";
;
CDS_SEC"1"
CDS_LOCATION"R1W11"
VALUE"0.0"
LOCATION"R1W11"
MATERIAL"EMPTY"
WATTAGE"1/8W"
TOLERANCE"5%"
PART_NUMBER"G22179-004"
PACK_TYPE"0805"
SEC"1"
SEC_TYPE"0805"
CDS_LIB"mstr_discrete";
"B"
$PN"2"65;
"A"
$PN"1"1;
%"P5V_STBY"
"1","(-5350,4150)","0","mstr_symbols","I134";
;
HDL_POWER"P5V_STBY"
BODY_TYPE"PLUMBING"
VOLTAGE"5.0V"
SIZE"1B"
CDS_LIB"mstr_symbols";
"G\NAC"9;
%"RES"
"1","(-5650,3225)","0","mstr_discrete","I137";
;
CDS_SEC"1"
CDS_LOCATION"R1W12"
PART_NUMBER"G21497-005"
LOCATION"R1W12"
VALUE"0.0"
MATERIAL"CHIP"
TOLERANCE"5%"
WATTAGE"1/16W"
PACK_TYPE"0402"
SEC"1"
SEC_TYPE"0402"
CDS_LIB"mstr_discrete"
ROOM"CPU0"
BOM_COST"PROC_SIDEBAND";
"B"
$PN"2"37;
"A"
$PN"1"36;
%"RES"
"1","(-5650,3000)","0","mstr_discrete","I138";
;
CDS_SEC"1"
CDS_LOCATION"R1W13"
POP"NOPOP"
WATTAGE"1/16W"
PACK_TYPE"0402"
VALUE"0.0"
LOCATION"R1W13"
TOLERANCE"5%"
MATERIAL"CHIP"
PART_NUMBER"G21497-005"
SEC"1"
SEC_TYPE"0402"
CDS_LIB"mstr_discrete"
ROOM"CPU0"
BOM_COST"PROC_SIDEBAND";
"B"
$PN"2"37;
"A"
$PN"1"58;
%"CAP_A"
"1","(-200,1500)","0","dev_discrete","I139";
;
LOCATION"C6W10"
VALUE"0.1UF"
VOLTAGE"16V"
TOLERANCE"10%"
MATERIAL"X7R"
PACK_TYPE"0402V"
PART_NUMBER"A36096-030"
SEC"1"
SEC_TYPE"0402V"
ROOM"VDDQ_KLM_PWR_VR"
CDS_SEC"1"
CDS_LIB"dev_discrete"
CDS_LOCATION"C6W10";
"B"
$PN"2"7;
"A"
$PN"1"8;
%"P3V3_STBY"
"1","(-1550,1800)","0","mstr_symbols","I140";
;
SIZE"1B"
BODY_TYPE"PLUMBING"
CDS_LIB"mstr_symbols"
VOLTAGE"3.3V"
HDL_POWER"P3V3_STBY";
"G\NAC"10;
%"RES"
"1","(-1350,3900)","0","mstr_discrete","I142";
;
CDS_SEC"1"
LOCATION"R1W33"
PART_NUMBER"G21497-005"
PACK_TYPE"0402"
VALUE"0.0"
TOLERANCE"5%"
WATTAGE"1/16W"
CDS_LOCATION"R1W33"
SEC"1"
SEC_TYPE"0402"
ROOM"CPU0"
MATERIAL"CHIP"
BOM_COST"PROC_SIDEBAND"
CDS_LIB"mstr_discrete";
"B"
$PN"2"57;
"A"
$PN"1"49;
%"RES"
"1","(-1350,3850)","0","mstr_discrete","I143";
;
CDS_SEC"1"
LOCATION"R1W34"
WATTAGE"1/16W"
TOLERANCE"5%"
PACK_TYPE"0402"
VALUE"0.0"
PART_NUMBER"G21497-005"
CDS_LOCATION"R1W34"
SEC"1"
SEC_TYPE"0402"
ROOM"CPU0"
MATERIAL"CHIP"
BOM_COST"PROC_SIDEBAND"
CDS_LIB"mstr_discrete";
"B"
$PN"2"56;
"A"
$PN"1"43;
%"TTL1G126_A"
"1","(-2500,1400)","6","mstr_ttl","I146";
;
CDS_SEC"1"
PART_NUMBER"A79322-001"
LOCATION"U6W4"
MATERIAL"IC"
VALUE"74HC1G126"
POWER_GROUP"VCC=P3V3_STBY;GND=GND;"
PACK_TYPE"SOT"
ROOM"SB"
SEC"1"
CDS_LIB"mstr_ttl"
SEC_TYPE"SOT"
BOM_COST"SB"
CDS_LOCATION"U6W4";
"OE"
$PN"1"28;
"Y"
$PN"4"25;
"A"
$PN"2"32;
%"RES"
"2","(-1550,1600)","0","mstr_discrete","I147";
;
CDS_SEC"1"
TOLERANCE"1%"
MATERIAL"CHIP"
PART_NUMBER"G22026-050"
PACK_TYPE"0603"
WATTAGE"1/10W"
VALUE"100.0K"
LOCATION"R6W30"
CDS_LIB"mstr_discrete"
ROOM"CPU0"
BOM_COST"PROC_SOCKET"
SEC"1"
SEC_TYPE"0603"
CDS_LOCATION"R6W30";
"A"
$PN"1"10;
"B"
$PN"2"25;
%"TTL1G126_A"
"1","(-1550,3150)","6","mstr_ttl","I148";
;
CDS_SEC"1"
VALUE"74HC1G126"
PART_NUMBER"A79322-001"
MATERIAL"IC"
LOCATION"U6W5"
POWER_GROUP"VCC=P3V3_STBY;GND=GND;"
PACK_TYPE"SOT"
ROOM"SB"
SEC"1"
CDS_LIB"mstr_ttl"
SEC_TYPE"SOT"
BOM_COST"SB"
CDS_LOCATION"U6W5";
"OE"
$PN"1"45;
"Y"
$PN"4"41;
"A"
$PN"2"48;
%"GND"
"1","(-750,3425)","0","mstr_symbols","I151";
;
CDS_LIB"mstr_symbols"
SIZE"1B"
VOLTAGE"0.0V"
BODY_TYPE"PLUMBING"
HDL_POWER"GND";
"A\NAC"11;
%"RES"
"2","(-1250,3525)","1","mstr_discrete","I156";
;
CDS_SEC"1"
TOLERANCE"1%"
LOCATION"R6W38"
VALUE"20.0K"
WATTAGE"1/16W"
PACK_TYPE"0402"
PART_NUMBER"G21796-040"
MATERIAL"CHIP"
CDS_LOCATION"R6W38"
SEC"1"
SEC_TYPE"0402"
CDS_LIB"mstr_discrete"
BOM_COST"SB"
ROOM"SB";
"A"
$PN"1"45;
"B"
$PN"2"11;
%"TTL1G126_A"
"1","(-1550,2600)","6","mstr_ttl","I157";
;
CDS_SEC"1"
PART_NUMBER"A79322-001"
LOCATION"U6W6"
MATERIAL"IC"
VALUE"74HC1G126"
POWER_GROUP"VCC=P3V3_STBY;GND=GND;"
CDS_LOCATION"U6W6"
PACK_TYPE"SOT"
ROOM"SB"
SEC"1"
CDS_LIB"mstr_ttl"
SEC_TYPE"SOT"
BOM_COST"SB";
"OE"
$PN"1"60;
"Y"
$PN"4"42;
"A"
$PN"2"48;
%"RES"
"2","(-1300,2950)","1","mstr_discrete","I158";
;
CDS_SEC"1"
CDS_LOCATION"R6W39"
VALUE"10.0K"
LOCATION"R6W39"
TOLERANCE"1%"
MATERIAL"CHIP"
WATTAGE"1/16W"
PACK_TYPE"0402"
PART_NUMBER"G21796-016"
BOM_COST"MIO_USB"
SEC_TYPE"0402"
SEC"1"
ROOM"USB_REAR"
CDS_LIB"mstr_discrete";
"A"
$PN"1"60;
"B"
$PN"2"12;
%"P3V3_STBY"
"1","(-650,2950)","0","mstr_symbols","I159";
;
SIZE"1B"
CDS_LIB"mstr_symbols"
VOLTAGE"3.3V"
BODY_TYPE"PLUMBING"
HDL_POWER"P3V3_STBY";
"G\NAC"12;
%"RES"
"1","(-5650,4600)","0","mstr_discrete","I16";
;
CDS_SEC"1"
WATTAGE"1/16W"
POP"NOPOP"
LOCATION"R1M5"
MATERIAL"CHIP"
PACK_TYPE"0402"
TOLERANCE"5%"
VALUE"0.0"
PART_NUMBER"G21497-005"
CDS_LOCATION"R1M5"
CDS_LIB"mstr_discrete"
SEC_TYPE"0402"
SEC"1"
BOM_COST"MIO_USB"
ROOM"USB_REAR";
"B"
$PN"2"33;
"A"
$PN"1"34;
%"RES"
"1","(-700,3150)","0","mstr_discrete","I160";
;
TOLERANCE"1%"
VALUE"10.0"
MATERIAL"CHIP"
WATTAGE"1/16W"
PART_NUMBER"G21796-066"
LOCATION"R6W37"
PACK_TYPE"0402"
CDS_LOCATION"R6W37"
CDS_LIB"mstr_discrete"
BOM_COST"SM_CONTROLLER"
CDS_SEC"1"
$SEC"1"
ROOM"MEM";
"B"
$PN"2"67;
"A"
$PN"1"41;
%"RES"
"1","(-725,2600)","0","mstr_discrete","I161";
;
WATTAGE"1/16W"
MATERIAL"CHIP"
PACK_TYPE"0402"
LOCATION"R6W36"
TOLERANCE"1%"
PART_NUMBER"G21796-066"
VALUE"10.0"
CDS_LOCATION"R6W36"
ROOM"MEM"
$SEC"1"
CDS_SEC"1"
BOM_COST"SM_CONTROLLER"
CDS_LIB"mstr_discrete";
"B"
$PN"2"66;
"A"
$PN"1"42;
%"PCA9617"
"1","(-4900,2000)","0","mstr_digital","I162";
;
MATERIAL"IC"
LOCATION"U1W3"
PART_NUMBER"G81764-001"
POWER_GROUP"GND=GND"
CDS_LOCATION"U1W3"
PACK_TYPE"SSOP"
CDS_LIB"mstr_digital"
BOM_COST"SM_CONTROLLER"
CDS_SEC"1"
$SEC"1"
ROOM"MEM";
"VCCA"
$PN"1"18;
"SCLA"
$PN"2"46;
"SDAA"
$PN"3"47;
"SCLB"
$PN"7"50;
"SDAB"
$PN"6"68;
"VCCB"
$PN"8"17;
"EN"
$PN"5"63;
%"CAP_A"
"1","(-4175,1650)","0","dev_discrete","I163";
;
LOCATION"C1W18"
PART_NUMBER"A36096-030"
VOLTAGE"16V"
MATERIAL"X7R"
VALUE"0.1UF"
PACK_TYPE"0402V"
TOLERANCE"10%"
CDS_LOCATION"C1W18"
$SEC"1"
CDS_SEC"1"
CDS_LIB"dev_discrete"
SIGNAL_MODEL"DEFAULT_CAPACITOR_100000pF_2_1"
CD_SEC"1"
BOM_COST"SM_CONTROLLER"
ROOM"MEM";
"B"
$PN"2"13;
"A"
$PN"1"15;
%"GND"
"1","(-4175,1450)","0","mstr_symbols","I164";
;
HDL_POWER"GND"
BODY_TYPE"PLUMBING"
VOLTAGE"0"
CDS_LIB"mstr_symbols"
SIZE"1B"
BOM_COST"SM_CONTROLLER"
ROOM"SMB";
"A\NAC"13;
%"CAP_A"
"1","(-3775,1650)","0","dev_discrete","I166";
;
PACK_TYPE"0402V"
TOLERANCE"10%"
VALUE"0.1UF"
MATERIAL"X7R"
LOCATION"C1W19"
PART_NUMBER"A36096-030"
VOLTAGE"16V"
CDS_LOCATION"C1W19"
ROOM"MEM"
CD_SEC"1"
SIGNAL_MODEL"DEFAULT_CAPACITOR_100000pF_2_1"
BOM_COST"SM_CONTROLLER"
CDS_LIB"dev_discrete"
CDS_SEC"1"
$SEC"1";
"B"
$PN"2"14;
"A"
$PN"1"16;
%"GND"
"1","(-3775,1450)","0","mstr_symbols","I167";
;
ROOM"SMB"
SIZE"1B"
CDS_LIB"mstr_symbols"
BOM_COST"SM_CONTROLLER"
VOLTAGE"0"
BODY_TYPE"PLUMBING"
HDL_POWER"GND";
"A\NAC"14;
%"P3V3_STBY"
"1","(-4175,1850)","0","mstr_symbols","I168";
;
HDL_POWER"P3V3_STBY"
BODY_TYPE"PLUMBING"
VOLTAGE"3.3V"
SIZE"1B"
CDS_LIB"mstr_symbols";
"G\NAC"15;
%"P3V3_STBY"
"1","(-3775,1850)","0","mstr_symbols","I169";
;
HDL_POWER"P3V3_STBY"
BODY_TYPE"PLUMBING"
VOLTAGE"3.3V"
SIZE"1B"
CDS_LIB"mstr_symbols";
"G\NAC"16;
%"P3V3_STBY"
"1","(-4400,2300)","0","mstr_symbols","I170";
;
HDL_POWER"P3V3_STBY"
BODY_TYPE"PLUMBING"
VOLTAGE"3.3V"
SIZE"1B"
CDS_LIB"mstr_symbols";
"G\NAC"17;
%"P3V3_STBY"
"1","(-5400,2300)","0","mstr_symbols","I171";
;
CDS_LIB"mstr_symbols"
SIZE"1B"
VOLTAGE"3.3V"
BODY_TYPE"PLUMBING"
HDL_POWER"P3V3_STBY";
"G\NAC"18;
%"RES"
"1","(-6100,2250)","5","mstr_discrete","I172";
;
CDS_SEC"1"
CDS_LOCATION"R1W36"
MATERIAL"CHIP"
PART_NUMBER"G21796-072"
PACK_TYPE"0402"
WATTAGE"1/16W"
TOLERANCE"1%"
VALUE"4.75K"
LOCATION"R1W36"
CDS_LIB"mstr_discrete"
SEC_TYPE"0402"
SEC"1";
"B"
$PN"2"46;
"A"
$PN"1"19;
%"RES"
"1","(-5800,2250)","5","mstr_discrete","I173";
;
CDS_SEC"1"
CDS_LOCATION"R1W37"
WATTAGE"1/16W"
PACK_TYPE"0402"
PART_NUMBER"G21796-072"
MATERIAL"CHIP"
VALUE"4.75K"
LOCATION"R1W37"
TOLERANCE"1%"
CDS_LIB"mstr_discrete"
SEC_TYPE"0402"
SEC"1";
"B"
$PN"2"47;
"A"
$PN"1"19;
%"P3V3_STBY"
"1","(-6100,2550)","0","mstr_symbols","I174";
;
HDL_POWER"P3V3_STBY"
BODY_TYPE"PLUMBING"
VOLTAGE"3.3V"
SIZE"1B"
CDS_LIB"mstr_symbols";
"G\NAC"19;
%"RES"
"1","(-5950,1550)","0","mstr_discrete","I175";
;
CDS_SEC"1"
POP"NOPOP"
LOCATION"R1W39"
VALUE"0.0"
PART_NUMBER"G21497-005"
PACK_TYPE"0402"
TOLERANCE"5%"
WATTAGE"1/16W"
CDS_LOCATION"R1W39"
CDS_LIB"mstr_discrete"
BOM_COST"PROC_SIDEBAND"
MATERIAL"CHIP"
ROOM"CPU0"
SEC_TYPE"0402"
SEC"1";
"B"
$PN"2"69;
"A"
$PN"1"51;
%"RES"
"1","(-5950,1600)","0","mstr_discrete","I176";
;
CDS_SEC"1"
WATTAGE"1/16W"
TOLERANCE"5%"
VALUE"0.0"
PACK_TYPE"0402"
LOCATION"R1W38"
PART_NUMBER"G21497-005"
POP"NOPOP"
CDS_LOCATION"R1W38"
CDS_LIB"mstr_discrete"
BOM_COST"PROC_SIDEBAND"
MATERIAL"CHIP"
ROOM"CPU0"
SEC_TYPE"0402"
SEC"1";
"B"
$PN"2"70;
"A"
$PN"1"52;
%"RES"
"1","(-2150,4950)","5","mstr_discrete","I178";
;
CDS_SEC"1"
CDS_LOCATION"R6W50"
VALUE"4.75K"
TOLERANCE"1%"
LOCATION"R6W50"
PACK_TYPE"0402"
WATTAGE"1/16W"
POP"NOPOP"
PART_NUMBER"G21796-072"
MATERIAL"CHIP"
CDS_LIB"mstr_discrete"
SEC_TYPE"0402"
SEC"1";
"B"
$PN"2"30;
"A"
$PN"1"20;
%"P3V3_STBY"
"1","(-2150,5200)","0","mstr_symbols","I179";
;
HDL_POWER"P3V3_STBY"
BODY_TYPE"PLUMBING"
VOLTAGE"3.3V"
SIZE"1B"
CDS_LIB"mstr_symbols";
"G\NAC"20;
%"CHOKE_4PIN"
"1","(-5500,5025)","0","mstr_discrete","I181";
;
CDS_SEC"1"
CDS_LOCATION"L1M2"
VALUE"90 OHM"
MATERIAL"IND"
LOCATION"L1M2"
PART_NUMBER"752402-015"
PACK_TYPE"SMLF"
SEC"1"
SEC_TYPE"SMLF"
CDS_LIB"mstr_discrete";
"B1"
$PN"3"33;
"B2"
$PN"4"31;
"A2"
$PN"2"34;
"A1"
$PN"1"35;
%"NC7SB3157"
"1","(-750,1850)","0","mstr_analog","I182";
;
CDS_LOCATION"U6W12"
LOCATION"U6W12"
PACK_TYPE"SMLF"
MATERIAL"IC"
PART_NUMBER"C99406-001"
BOM_COST"DEBUG"
CDS_LIB"mstr_analog"
CDS_SEC"1"
$SEC"1"
ROOM"DEBUG";
"GND"
$PN"2"21;
"A"
$PN"4"26;
"VCC"
$PN"5"8;
"B1"
$PN"1"25;
"B0"
$PN"3"27;
"S"
$PN"6"29;
%"GND"
"1","(-350,1650)","0","mstr_symbols","I183";
;
HDL_POWER"GND"
BODY_TYPE"PLUMBING"
VOLTAGE"0.0V"
CDS_LIB"mstr_symbols"
SIZE"1B";
"A\NAC"21;
%"RES"
"1","(-5650,5550)","0","mstr_discrete","I31";
;
CDS_SEC"1"
WATTAGE"1/16W"
VALUE"0.0"
MATERIAL"CHIP"
TOLERANCE"5%"
LOCATION"R1M6"
POP"NOPOP"
PACK_TYPE"0402"
PART_NUMBER"G21497-005"
CDS_LOCATION"R1M6"
CDS_LIB"mstr_discrete"
ROOM"USB"
BOM_COST"MIO_USB"
SEC_TYPE"0402"
SEC"1";
"B"
$PN"2"31;
"A"
$PN"1"35;
%"CONN9_H51826001"
"2","(-1300,4550)","0","mstr_conn","I69";
;
MATERIAL"CONN"
PART_NUMBER"H51826-001"
LOCATION"J9B1"
CDS_LIB"mstr_conn"
$SEC"1"
CDS_SEC"1"
PACK_TYPE"PIP2"
CDS_LOCATION"J9B1"
ROOM"USB_REAR";
"STDA_SSRXN"
$PN"5"54;
"STDA_SSRXP"
$PN"6"55;
"STDA_SSTXN"
$PN"8"44;
"STDA_SSTXP"
$PN"9"30;
"MH2"
$PN"MH2"22;
"MH1"
$PN"MH1"22;
"DN"
$PN"2"31;
"DP"
$PN"3"33;
"VBUS"
$PN"1"40;
"GND"
$PN"4"23;
"MH4"
$PN"MH4"23;
"MH3"
$PN"MH3"23;
"GND_DRAIN"
$PN"7"53;
%"GND"
"1","(-2550,4075)","0","mstr_symbols","I70";
;
CDS_LIB"mstr_symbols"
SIZE"1B"
VOLTAGE"0.0V"
BODY_TYPE"PLUMBING"
HDL_POWER"GND";
"A\NAC"22;
%"GND"
"1","(-50,4100)","0","mstr_symbols","I71";
;
CDS_LIB"mstr_symbols"
SIZE"1B"
VOLTAGE"0.0V"
BODY_TYPE"PLUMBING"
HDL_POWER"GND";
"A\NAC"23;
%"DIODEAC_DUAL_ARRAY"
"7","(-3950,4500)","0","mstr_discrete","I98";
;
CDS_SEC"1"
MATERIAL"IC"
LOCATION"CR1M2"
PART_NUMBER"G18435-001"
VALUE"ESD3V3U4ULC"
CDS_LIB"mstr_discrete"
ROOM"USB_REAR"
CDS_LOCATION"CR1M2"
SEC"1"
SEC_TYPE"SM9"
PACK_TYPE"SM9"
BOM_COST"MIO_USB";
"AC3"
$PN"5"38;
"AC2"
$PN"4"39;
"AC1"
$PN"2"31;
"AC0"
$PN"1"33;
"OUT3"
$PN"6"61;
"OUT2"
$PN"7"62;
"OUT1"
$PN"8"31;
"OUT0"
$PN"9"33;
"GND<0>"
$PN"3"24;
%"GND"
"1","(-3550,4250)","0","mstr_symbols","I99";
;
VOLTAGE"0.0V"
SIZE"1B"
CDS_LIB"mstr_symbols"
BODY_TYPE"PLUMBING"
HDL_POWER"GND";
"A\NAC"24;
END.
